(kicad_pcb
	(version 20241229)
	(generator "pcbnew")
	(generator_version "9.0")
	(general
		(thickness 1.711)
		(legacy_teardrops no)
	)
	(paper "A4")
	(title_block
		(title "Antmicro Baseboard for Jetson AGX Thor")
		(date "2026-02-18")
		(rev "1.1.0")
		(company "Antmicro Ltd")
		(comment 1 "www.antmicro.com")
		(comment 9 "footprints 767-771 of 1170")
	)
	(layers
		(0 "F.Cu" signal)
		(4 "In1.Cu" signal)
		(6 "In2.Cu" signal)
		(8 "In3.Cu" signal)
		(10 "In4.Cu" jumper)
		(12 "In5.Cu" signal)
		(14 "In6.Cu" signal)
		(16 "In7.Cu" signal)
		(18 "In8.Cu" signal)
		(2 "B.Cu" signal)
		(9 "F.Adhes" user "F.Adhesive")
		(11 "B.Adhes" user "B.Adhesive")
		(13 "F.Paste" user)
		(15 "B.Paste" user)
		(5 "F.SilkS" user "F.Silkscreen")
		(7 "B.SilkS" user "B.Silkscreen")
		(1 "F.Mask" user)
		(3 "B.Mask" user)
		(17 "Dwgs.User" user "User.Drawings")
		(19 "Cmts.User" user "User.Comments")
		(21 "Eco1.User" user "User.Eco1")
		(23 "Eco2.User" user "User.Eco2")
		(25 "Edge.Cuts" user)
		(27 "Margin" user)
		(31 "F.CrtYd" user "F.Courtyard")
		(29 "B.CrtYd" user "B.Courtyard")
		(35 "F.Fab" user)
		(33 "B.Fab" user)
	)
	(footprint "antmicro-footprints:C_0402_1005Metric"
		(layer "B.Cu")
		(at 207.226 139.6)
		(descr "Capacitor SMD 0402")
		(tags "capacitor SMD 0402")
		(property "Reference" "C177"
			(at 1.1 -0.4 0)
			(layer "B.SilkS")
			(effects
				(font
					(size 0.7 0.7)
					(thickness 0.15)
				)
				(justify right top mirror)
			)
		)
		(property "Value" "C_100n_0402"
			(at -1.022927 -2.155213 0)
			(layer "B.Fab")
			(effects
				(font
					(size 0.7 0.7)
					(thickness 0.15)
				)
				(justify right top mirror)
			)
		)
		(property "Datasheet" "https://www.murata.com/products/productdetail?partno=GRM155R61H104KE14%23"
			(at 0 0 0)
			(layer "B.Fab")
			(hide yes)
			(effects
				(font
					(size 1.27 1.27)
					(thickness 0.15)
				)
				(justify mirror)
			)
		)
		(property "Description" "SMD Multilayer Ceramic Capacitor, 0.1 µF, 50 V, 0402 [1005 Metric], ± 10%, X5R, GRM Series"
			(at 0 0 0)
			(layer "B.Fab")
			(hide yes)
			(effects
				(font
					(size 1.27 1.27)
					(thickness 0.15)
				)
				(justify mirror)
			)
		)
		(property "MPN" "GRM155R61H104KE14D"
			(at 0 0 180)
			(unlocked yes)
			(layer "B.Fab")
			(hide yes)
			(effects
				(font
					(size 1 1)
					(thickness 0.15)
				)
				(justify mirror)
			)
		)
		(property "Manufacturer" "Murata"
			(at 0 0 180)
			(unlocked yes)
			(layer "B.Fab")
			(hide yes)
			(effects
				(font
					(size 1 1)
					(thickness 0.15)
				)
				(justify mirror)
			)
		)
		(property "License" "Apache-2.0"
			(at 0 0 180)
			(unlocked yes)
			(layer "B.Fab")
			(hide yes)
			(effects
				(font
					(size 1 1)
					(thickness 0.15)
				)
				(justify mirror)
			)
		)
		(property "Author" "Antmicro"
			(at 0 0 180)
			(unlocked yes)
			(layer "B.Fab")
			(hide yes)
			(effects
				(font
					(size 1 1)
					(thickness 0.15)
				)
				(justify mirror)
			)
		)
		(property "Val" "100n"
			(at 0 0 180)
			(unlocked yes)
			(layer "B.Fab")
			(hide yes)
			(effects
				(font
					(size 1 1)
					(thickness 0.15)
				)
				(justify mirror)
			)
		)
		(property "Voltage" "50V"
			(at 0 0 180)
			(unlocked yes)
			(layer "B.Fab")
			(hide yes)
			(effects
				(font
					(size 1 1)
					(thickness 0.15)
				)
				(justify mirror)
			)
		)
		(property "Dielectric" "X5R"
			(at 0 0 180)
			(unlocked yes)
			(layer "B.Fab")
			(hide yes)
			(effects
				(font
					(size 1 1)
					(thickness 0.15)
				)
				(justify mirror)
			)
		)
		(sheetname "/SFP/")
		(sheetfile "sfp.kicad_sch")
		(attr smd)
		(fp_rect
			(start -0.925 0.47)
			(end 0.925 -0.47)
			(stroke
				(width 0.05)
				(type default)
			)
			(fill no)
			(layer "B.CrtYd")
		)
		(fp_line
			(start -0.494 -0.248)
			(end -0.494 0.25)
			(stroke
				(width 0.15)
				(type solid)
			)
			(layer "B.Fab")
		)
		(fp_line
			(start -0.494 0.25)
			(end 0.504 0.25)
			(stroke
				(width 0.15)
				(type solid)
			)
			(layer "B.Fab")
		)
		(fp_line
			(start 0.504 -0.248)
			(end -0.494 -0.248)
			(stroke
				(width 0.15)
				(type solid)
			)
			(layer "B.Fab")
		)
		(fp_line
			(start 0.504 0.25)
			(end 0.504 -0.248)
			(stroke
				(width 0.15)
				(type solid)
			)
			(layer "B.Fab")
		)
		(fp_text user "Author: Antmicro"
			(at -0.939 -3.399 0)
			(layer "B.Fab")
			(effects
				(font
					(size 0.7 0.7)
					(thickness 0.15)
				)
				(justify right top mirror)
			)
		)
		(fp_text user "License: Apache-2.0"
			(at -0.939 -5.799 0)
			(layer "B.Fab")
			(effects
				(font
					(size 0.7 0.7)
					(thickness 0.15)
				)
				(justify right top mirror)
			)
		)
		(fp_text user "${REFERENCE}"
			(at -0.939 -4.599 0)
			(layer "B.Fab")
			(effects
				(font
					(size 0.7 0.7)
					(thickness 0.15)
				)
				(justify right top mirror)
			)
		)
		(pad "1" smd roundrect
			(at -0.48 0)
			(size 0.59 0.64)
			(layers "B.Cu" "B.Mask" "B.Paste")
			(roundrect_rratio 0.25)
			(net 1 "GND")
			(pintype "passive")
		)
		(pad "2" smd roundrect
			(at 0.48 0)
			(size 0.59 0.64)
			(layers "B.Cu" "B.Mask" "B.Paste")
			(roundrect_rratio 0.25)
			(net 379 "/SFP/SH")
			(pintype "passive")
		)
	)
	(footprint "antmicro-footprints:TP_SMD_0.75mm"
		(layer "B.Cu")
		(at 137 75.2 -45)
		(property "Reference" "TP106"
			(at 1.909188 0.494975 0)
			(layer "B.SilkS")
			(effects
				(font
					(size 0.7 0.7)
					(thickness 0.15)
				)
				(justify left bottom mirror)
			)
		)
		(property "Value" "TP_0.75mm_SMD"
			(at 0 -1.2 135)
			(layer "B.Fab")
			(effects
				(font
					(size 0.7 0.7)
					(thickness 0.15)
				)
				(justify left bottom mirror)
			)
		)
		(property "Description" "SMT test point"
			(at 0 0 135)
			(layer "B.Fab")
			(hide yes)
			(effects
				(font
					(size 1.27 1.27)
					(thickness 0.15)
				)
				(justify mirror)
			)
		)
		(property "MPN" ""
			(at 0 0 135)
			(unlocked yes)
			(layer "B.Fab")
			(hide yes)
			(effects
				(font
					(size 1 1)
					(thickness 0.15)
				)
				(justify mirror)
			)
		)
		(property "Manufacturer" ""
			(at 0 0 135)
			(unlocked yes)
			(layer "B.Fab")
			(hide yes)
			(effects
				(font
					(size 1 1)
					(thickness 0.15)
				)
				(justify mirror)
			)
		)
		(property "Author" "Antmicro"
			(at 0 0 135)
			(unlocked yes)
			(layer "B.Fab")
			(hide yes)
			(effects
				(font
					(size 1 1)
					(thickness 0.15)
				)
				(justify mirror)
			)
		)
		(property "License" "Apache-2.0"
			(at 0 0 135)
			(unlocked yes)
			(layer "B.Fab")
			(hide yes)
			(effects
				(font
					(size 1 1)
					(thickness 0.15)
				)
				(justify mirror)
			)
		)
		(sheetname "/SoM_IO/")
		(sheetfile "som_io.kicad_sch")
		(attr exclude_from_pos_files exclude_from_bom)
		(fp_circle
			(center 0 0)
			(end 0.475 0)
			(stroke
				(width 0.05)
				(type default)
			)
			(fill no)
			(layer "B.CrtYd")
		)
		(fp_text user "Author: Antmicro"
			(at -0.4 -3.901 135)
			(layer "B.Fab")
			(effects
				(font
					(size 0.7 0.7)
					(thickness 0.15)
				)
				(justify left bottom mirror)
			)
		)
		(fp_text user "License: Apache-2.0"
			(at -0.4 -5.101 135)
			(layer "B.Fab")
			(effects
				(font
					(size 0.7 0.7)
					(thickness 0.15)
				)
				(justify left bottom mirror)
			)
		)
		(fp_text user "${REFERENCE}"
			(at -0.4 -2.7 135)
			(layer "B.Fab")
			(effects
				(font
					(size 0.7 0.7)
					(thickness 0.15)
				)
				(justify left bottom mirror)
			)
		)
		(pad "1" smd circle
			(at 0 0 315)
			(size 0.75 0.75)
			(layers "B.Cu" "B.Mask")
			(net 243 "/SoM_IO/UART1.CTS")
			(pinfunction "1")
			(pintype "passive")
		)
	)
	(footprint "antmicro-footprints:R_0402_1005Metric"
		(layer "B.Cu")
		(at 157.14 65.5 180)
		(descr "Resistor SMD 0402")
		(tags "resistor SMD 0402")
		(property "Reference" "R294"
			(at -1.06 -4.3 0)
			(layer "B.SilkS")
			(effects
				(font
					(size 0.7 0.7)
					(thickness 0.15)
				)
				(justify left bottom mirror)
			)
		)
		(property "Value" "R_0R_0402"
			(at -1.011843 -1.772047 0)
			(layer "B.Fab")
			(effects
				(font
					(size 0.7 0.7)
					(thickness 0.15)
				)
				(justify left bottom mirror)
			)
		)
		(property "Datasheet" "https://industrial.panasonic.com/cdbs/www-data/pdf/RDA0000/AOA0000C301.pdf"
			(at 0 0 0)
			(layer "B.Fab")
			(hide yes)
			(effects
				(font
					(size 1.27 1.27)
					(thickness 0.15)
				)
				(justify mirror)
			)
		)
		(property "Description" "SMD Chip Resistor, Jumper, 0 ohm, 100 mW, 0402 [1005 Metric], Thick Film, General Purpose"
			(at 0 0 0)
			(layer "B.Fab")
			(hide yes)
			(effects
				(font
					(size 1.27 1.27)
					(thickness 0.15)
				)
				(justify mirror)
			)
		)
		(property "MPN" "ERJ2GE0R00X"
			(at 0 0 0)
			(unlocked yes)
			(layer "B.Fab")
			(hide yes)
			(effects
				(font
					(size 1 1)
					(thickness 0.15)
				)
				(justify mirror)
			)
		)
		(property "Manufacturer" "Panasonic"
			(at 0 0 0)
			(unlocked yes)
			(layer "B.Fab")
			(hide yes)
			(effects
				(font
					(size 1 1)
					(thickness 0.15)
				)
				(justify mirror)
			)
		)
		(property "License" "Apache-2.0"
			(at 0 0 0)
			(unlocked yes)
			(layer "B.Fab")
			(hide yes)
			(effects
				(font
					(size 1 1)
					(thickness 0.15)
				)
				(justify mirror)
			)
		)
		(property "Author" "Antmicro"
			(at 0 0 0)
			(unlocked yes)
			(layer "B.Fab")
			(hide yes)
			(effects
				(font
					(size 1 1)
					(thickness 0.15)
				)
				(justify mirror)
			)
		)
		(property "Val" "0R"
			(at 0 0 0)
			(unlocked yes)
			(layer "B.Fab")
			(hide yes)
			(effects
				(font
					(size 1 1)
					(thickness 0.15)
				)
				(justify mirror)
			)
		)
		(property "Tolerance" "~"
			(at 0 0 0)
			(unlocked yes)
			(layer "B.Fab")
			(hide yes)
			(effects
				(font
					(size 1 1)
					(thickness 0.15)
				)
				(justify mirror)
			)
		)
		(property "Current" "1A"
			(at 0 0 0)
			(unlocked yes)
			(layer "B.Fab")
			(hide yes)
			(effects
				(font
					(size 1 1)
					(thickness 0.15)
				)
				(justify mirror)
			)
		)
		(sheetname "/SoM_IO2/")
		(sheetfile "som_io2.kicad_sch")
		(attr smd exclude_from_pos_files exclude_from_bom dnp)
		(fp_rect
			(start -0.925 0.47)
			(end 0.925 -0.47)
			(stroke
				(width 0.05)
				(type default)
			)
			(fill no)
			(layer "B.CrtYd")
		)
		(fp_rect
			(start -0.5 0.25)
			(end 0.5 -0.25)
			(stroke
				(width 0.15)
				(type solid)
			)
			(fill no)
			(layer "B.Fab")
		)
		(fp_text user "License: Apache-2.0"
			(at -0.95 -5.169 0)
			(layer "B.Fab")
			(effects
				(font
					(size 0.7 0.7)
					(thickness 0.15)
				)
				(justify left bottom mirror)
			)
		)
		(fp_text user "${REFERENCE}"
			(at -0.95 -3.168 0)
			(layer "B.Fab")
			(effects
				(font
					(size 0.7 0.7)
					(thickness 0.15)
				)
				(justify left bottom mirror)
			)
		)
		(fp_text user "Author: Antmicro"
			(at -0.95 -4.169 0)
			(layer "B.Fab")
			(effects
				(font
					(size 0.7 0.7)
					(thickness 0.15)
				)
				(justify left bottom mirror)
			)
		)
		(pad "1" smd roundrect
			(at -0.48 0 180)
			(size 0.59 0.64)
			(layers "B.Cu" "B.Mask" "B.Paste")
			(roundrect_rratio 0.25)
			(net 1030 "Net-(U59-B1Y)")
			(pintype "passive")
		)
		(pad "2" smd roundrect
			(at 0.48 0 180)
			(size 0.59 0.64)
			(layers "B.Cu" "B.Mask" "B.Paste")
			(roundrect_rratio 0.25)
			(net 706 "/SoM_IO2/JTAG_TMS")
			(pintype "passive")
		)
	)
	(footprint "antmicro-footprints:R_0402_1005Metric"
		(layer "B.Cu")
		(at 71.1 67.3)
		(descr "Resistor SMD 0402")
		(tags "resistor SMD 0402")
		(property "Reference" "R395"
			(at 0.9 -0.3 0)
			(layer "B.SilkS")
			(effects
				(font
					(size 0.7 0.7)
					(thickness 0.15)
				)
				(justify right top mirror)
			)
		)
		(property "Value" "R_0R_0402"
			(at -1.011843 -1.772047 0)
			(layer "B.Fab")
			(effects
				(font
					(size 0.7 0.7)
					(thickness 0.15)
				)
				(justify right top mirror)
			)
		)
		(property "Datasheet" "https://industrial.panasonic.com/cdbs/www-data/pdf/RDA0000/AOA0000C301.pdf"
			(at 0 0 0)
			(layer "B.Fab")
			(hide yes)
			(effects
				(font
					(size 1.27 1.27)
					(thickness 0.15)
				)
				(justify mirror)
			)
		)
		(property "Description" "SMD Chip Resistor, Jumper, 0 ohm, 100 mW, 0402 [1005 Metric], Thick Film, General Purpose"
			(at 0 0 0)
			(layer "B.Fab")
			(hide yes)
			(effects
				(font
					(size 1.27 1.27)
					(thickness 0.15)
				)
				(justify mirror)
			)
		)
		(property "MPN" "ERJ2GE0R00X"
			(at 0 0 180)
			(unlocked yes)
			(layer "B.Fab")
			(hide yes)
			(effects
				(font
					(size 1 1)
					(thickness 0.15)
				)
				(justify mirror)
			)
		)
		(property "Manufacturer" "Panasonic"
			(at 0 0 180)
			(unlocked yes)
			(layer "B.Fab")
			(hide yes)
			(effects
				(font
					(size 1 1)
					(thickness 0.15)
				)
				(justify mirror)
			)
		)
		(property "License" "Apache-2.0"
			(at 0 0 180)
			(unlocked yes)
			(layer "B.Fab")
			(hide yes)
			(effects
				(font
					(size 1 1)
					(thickness 0.15)
				)
				(justify mirror)
			)
		)
		(property "Author" "Antmicro"
			(at 0 0 180)
			(unlocked yes)
			(layer "B.Fab")
			(hide yes)
			(effects
				(font
					(size 1 1)
					(thickness 0.15)
				)
				(justify mirror)
			)
		)
		(property "Val" "0R"
			(at 0 0 180)
			(unlocked yes)
			(layer "B.Fab")
			(hide yes)
			(effects
				(font
					(size 1 1)
					(thickness 0.15)
				)
				(justify mirror)
			)
		)
		(property "Tolerance" "~"
			(at 0 0 180)
			(unlocked yes)
			(layer "B.Fab")
			(hide yes)
			(effects
				(font
					(size 1 1)
					(thickness 0.15)
				)
				(justify mirror)
			)
		)
		(property "Current" "1A"
			(at 0 0 180)
			(unlocked yes)
			(layer "B.Fab")
			(hide yes)
			(effects
				(font
					(size 1 1)
					(thickness 0.15)
				)
				(justify mirror)
			)
		)
		(sheetname "/CSI/")
		(sheetfile "csi.kicad_sch")
		(attr smd)
		(fp_rect
			(start -0.925 0.47)
			(end 0.925 -0.47)
			(stroke
				(width 0.05)
				(type default)
			)
			(fill no)
			(layer "B.CrtYd")
		)
		(fp_rect
			(start -0.5 0.25)
			(end 0.5 -0.25)
			(stroke
				(width 0.15)
				(type solid)
			)
			(fill no)
			(layer "B.Fab")
		)
		(fp_text user "${REFERENCE}"
			(at -0.95 -3.168 0)
			(layer "B.Fab")
			(effects
				(font
					(size 0.7 0.7)
					(thickness 0.15)
				)
				(justify right top mirror)
			)
		)
		(fp_text user "License: Apache-2.0"
			(at -0.95 -5.169 0)
			(layer "B.Fab")
			(effects
				(font
					(size 0.7 0.7)
					(thickness 0.15)
				)
				(justify right top mirror)
			)
		)
		(fp_text user "Author: Antmicro"
			(at -0.95 -4.169 0)
			(layer "B.Fab")
			(effects
				(font
					(size 0.7 0.7)
					(thickness 0.15)
				)
				(justify right top mirror)
			)
		)
		(pad "1" smd roundrect
			(at -0.48 0)
			(size 0.59 0.64)
			(layers "B.Cu" "B.Mask" "B.Paste")
			(roundrect_rratio 0.25)
			(net 993 "/CSI/SDA_CAM2")
			(pintype "passive")
		)
		(pad "2" smd roundrect
			(at 0.48 0)
			(size 0.59 0.64)
			(layers "B.Cu" "B.Mask" "B.Paste")
			(roundrect_rratio 0.25)
			(net 1373 "Net-(J10-Pad39)")
			(pintype "passive")
		)
	)
	(footprint "antmicro-footprints:C_0603_1608Metric_EIA"
		(layer "B.Cu")
		(at 124.6 113.5)
		(descr "Capacitor SMD 0603, IPC-7351 Density Level A")
		(tags "Capacitor 0603")
		(property "Reference" "C191"
			(at 1.2 -1.9 0)
			(layer "B.SilkS")
			(effects
				(font
					(size 0.7 0.7)
					(thickness 0.15)
				)
				(justify right top mirror)
			)
		)
		(property "Value" "C_22u_16V_0603"
			(at -1.42757 -1.770288 0)
			(layer "B.Fab")
			(effects
				(font
					(size 0.7 0.7)
					(thickness 0.15)
				)
				(justify right top mirror)
			)
		)
		(property "Datasheet" "https://product.samsungsem.com/mlcc/CL10A226MO7JZN.do"
			(at 0 0 0)
			(layer "B.Fab")
			(hide yes)
			(effects
				(font
					(size 1.27 1.27)
					(thickness 0.15)
				)
				(justify mirror)
			)
		)
		(property "Description" "SMD Multilayer Ceramic Capacitor"
			(at 0 0 0)
			(layer "B.Fab")
			(hide yes)
			(effects
				(font
					(size 1.27 1.27)
					(thickness 0.15)
				)
				(justify mirror)
			)
		)
		(property "Manufacturer" "Samsung Electro-Mechanics"
			(at 0 0 0)
			(unlocked yes)
			(layer "B.Fab")
			(hide yes)
			(effects
				(font
					(size 1 1)
					(thickness 0.15)
				)
				(justify mirror)
			)
		)
		(property "MPN" "CL10A226MO7JZNC"
			(at 0 0 0)
			(unlocked yes)
			(layer "B.Fab")
			(hide yes)
			(effects
				(font
					(size 1 1)
					(thickness 0.15)
				)
				(justify mirror)
			)
		)
		(property "Val" "22u"
			(at 0 0 0)
			(unlocked yes)
			(layer "B.Fab")
			(hide yes)
			(effects
				(font
					(size 1 1)
					(thickness 0.15)
				)
				(justify mirror)
			)
		)
		(property "License" "Apache-2.0"
			(at 0 0 0)
			(unlocked yes)
			(layer "B.Fab")
			(hide yes)
			(effects
				(font
					(size 1 1)
					(thickness 0.15)
				)
				(justify mirror)
			)
		)
		(property "Author" "Antmicro"
			(at 0 0 0)
			(unlocked yes)
			(layer "B.Fab")
			(hide yes)
			(effects
				(font
					(size 1 1)
					(thickness 0.15)
				)
				(justify mirror)
			)
		)
		(property "Voltage" "16V"
			(at 0 0 0)
			(unlocked yes)
			(layer "B.Fab")
			(hide yes)
			(effects
				(font
					(size 1 1)
					(thickness 0.15)
				)
				(justify mirror)
			)
		)
		(property "Dielectric" "template_dielectric"
			(at 0 0 0)
			(unlocked yes)
			(layer "B.Fab")
			(hide yes)
			(effects
				(font
					(size 1 1)
					(thickness 0.15)
				)
				(justify mirror)
			)
		)
		(sheetname "/M.2/")
		(sheetfile "m2.kicad_sch")
		(attr smd)
		(fp_line
			(start -0.15 -0.55)
			(end 0.15 -0.55)
			(stroke
				(width 0.15)
				(type solid)
			)
			(layer "B.SilkS")
		)
		(fp_line
			(start -0.15 0.55)
			(end 0.15 0.55)
			(stroke
				(width 0.15)
				(type solid)
			)
			(layer "B.SilkS")
		)
		(fp_poly
			(pts
				(xy -1.25 0.65) (xy -1.25 -0.65) (xy 1.25 -0.65) (xy 1.25 0.65)
			)
			(stroke
				(width 0.05)
				(type solid)
			)
			(fill no)
			(layer "B.CrtYd")
		)
		(fp_poly
			(pts
				(xy -0.799999 0.45) (xy -0.799999 -0.45) (xy 0.799999 -0.45) (xy 0.799999 0.45)
			)
			(stroke
				(width 0.15)
				(type solid)
			)
			(fill no)
			(layer "B.Fab")
		)
		(fp_text user "Author: Antmicro"
			(at -1.682 -4.894 0)
			(layer "B.Fab")
			(effects
				(font
					(size 0.7 0.7)
					(thickness 0.15)
				)
				(justify right top mirror)
			)
		)
		(fp_text user "${REFERENCE}"
			(at -1.682001 -3.895 0)
			(layer "B.Fab")
			(effects
				(font
					(size 0.7 0.7)
					(thickness 0.15)
				)
				(justify right top mirror)
			)
		)
		(fp_text user "License: Apache-2.0"
			(at -1.682 -5.895 0)
			(layer "B.Fab")
			(effects
				(font
					(size 0.7 0.7)
					(thickness 0.15)
				)
				(justify right top mirror)
			)
		)
		(pad "1" smd roundrect
			(at -0.7 0)
			(size 0.8 1.1)
			(layers "B.Cu" "B.Mask" "B.Paste")
			(roundrect_rratio 0.2)
			(net 14 "/M.2/3V3_M2")
			(pintype "passive")
		)
		(pad "2" smd roundrect
			(at 0.7 0)
			(size 0.8 1.1)
			(layers "B.Cu" "B.Mask" "B.Paste")
			(roundrect_rratio 0.2)
			(net 1 "GND")
			(pintype "passive")
		)
	)
)
